# T6G (Grand Teton) — schematic netlist excerpt (pin names and nets, part order shuffled) for the footprints in the layout excerpt that follows; sources: Cadence DE-HDL packaged netlist, KiCad conversion of 04192023_DAF0TMB3IC0_F0TG_MB_C_brd_V02_OCP.brd

PR3950  Q_RES  100 1% EMPTY  pkg 0402LF  page 147 : A = P12V_E1S_0 ; B = P12V_E1S_AVIN_PD_0
R3326  Q_RES  0 5% CHIP  pkg 0402LF  page 233 : A = GPU_FPGA_READY_N ; B = GPU_FPGA_READY_R_N

(kicad_pcb
	(version 20260206)
	(generator "pcbnew")
	(generator_version "10.0")
	(general
		(thickness 1.6)
		(legacy_teardrops no)
	)
	(paper "A4")
	(title_block
		(title "04192023_DAF0TMB3IC0_F0TG_MB_C_brd_V02_OCP.brd")
		(comment 1 "Grand Teton / footprints 2493-2494 of 8354")
	)
	(layers
		(0 "F.Cu" signal "TOP")
		(4 "In1.Cu" signal "GND")
		(6 "In2.Cu" signal "IN1")
		(8 "In3.Cu" signal "GND1")
		(10 "In4.Cu" signal "IN2")
		(12 "In5.Cu" signal "GND2")
		(14 "In6.Cu" signal "IN3")
		(16 "In7.Cu" signal "GND3")
		(18 "In8.Cu" signal "VCC")
		(20 "In9.Cu" signal "VCC1")
		(22 "In10.Cu" signal "GND4")
		(24 "In11.Cu" signal "IN4")
		(26 "In12.Cu" signal "GND5")
		(28 "In13.Cu" signal "IN5")
		(30 "In14.Cu" signal "GND6")
		(32 "In15.Cu" signal "IN6")
		(34 "In16.Cu" signal "GND7")
		(2 "B.Cu" signal "BOTTOM")
		(9 "F.Adhes" user "F.Adhesive")
		(11 "B.Adhes" user "B.Adhesive")
		(13 "F.Paste" user "Package Geometry/Pastemask Top")
		(15 "B.Paste" user "Package Geometry/Pastemask Bottom")
		(5 "F.SilkS" user "Ref Des/Silkscreen Top")
		(7 "B.SilkS" user "Ref Des/Silkscreen Bottom")
		(1 "F.Mask" user "Board Geometry/Soldermask Top")
		(3 "B.Mask" user "Board Geometry/Soldermask Bottom")
		(17 "Dwgs.User" user "User.Drawings")
		(19 "Cmts.User" user "User.Comments")
		(21 "Eco1.User" user "User.Eco1")
		(23 "Eco2.User" user "User.Eco2")
		(25 "Edge.Cuts" user "Board Geometry/Outline")
		(27 "Margin" user)
		(31 "F.CrtYd" user "Package Geometry/Place Bound Top")
		(29 "B.CrtYd" user "Package Geometry/Place Bound Bottom")
		(35 "F.Fab" user "Ref Des/Assembly Top")
		(33 "B.Fab" user "Ref Des/Assembly Bottom")
	)
	(footprint ""
		(layer "F.Cu")
		(at 248.20753 -53.193442 90)
		(property "Reference" "PR3950"
			(at 0 0 90)
			(layer "F.SilkS")
			(hide yes)
			(effects
				(font
					(size 1.27 1.27)
				)
			)
		)
		(property "Value" ""
			(at 0 0 90)
			(layer "F.Fab")
			(effects
				(font
					(size 1.27 1.27)
				)
			)
		)
		(duplicate_pad_numbers_are_jumpers no)
		(fp_line
			(start 0.7874 -0.4064)
			(end 0.7874 0.4064)
			(stroke
				(width 0.1524)
				(type default)
			)
			(layer "F.SilkS")
		)
		(fp_line
			(start -0.7874 -0.4064)
			(end 0.7874 -0.4064)
			(stroke
				(width 0.1524)
				(type default)
			)
			(layer "F.SilkS")
		)
		(fp_line
			(start 0.7874 0.4064)
			(end -0.7874 0.4064)
			(stroke
				(width 0.1524)
				(type default)
			)
			(layer "F.SilkS")
		)
		(fp_line
			(start -0.7874 0.4064)
			(end -0.7874 -0.4064)
			(stroke
				(width 0.1524)
				(type default)
			)
			(layer "F.SilkS")
		)
		(fp_line
			(start -0.12065 -0.305054)
			(end -0.12065 -0.2794)
			(stroke
				(width 0.1)
				(type default)
			)
			(layer "F.Fab")
		)
		(fp_line
			(start -0.67945 -0.305054)
			(end -0.12065 -0.305054)
			(stroke
				(width 0.1)
				(type default)
			)
			(layer "F.Fab")
		)
		(fp_line
			(start 0.67945 -0.3048)
			(end 0.67945 0.3048)
			(stroke
				(width 0.1)
				(type default)
			)
			(layer "F.Fab")
		)
		(fp_line
			(start 0.12065 -0.3048)
			(end 0.67945 -0.3048)
			(stroke
				(width 0.1)
				(type default)
			)
			(layer "F.Fab")
		)
		(fp_line
			(start 0.12065 -0.2794)
			(end 0.12065 -0.3048)
			(stroke
				(width 0.1)
				(type default)
			)
			(layer "F.Fab")
		)
		(fp_line
			(start -0.12065 -0.2794)
			(end 0.12065 -0.2794)
			(stroke
				(width 0.1)
				(type default)
			)
			(layer "F.Fab")
		)
		(fp_line
			(start 0.120396 0.2794)
			(end -0.12065 0.2794)
			(stroke
				(width 0.1)
				(type default)
			)
			(layer "F.Fab")
		)
		(fp_line
			(start -0.12065 0.2794)
			(end -0.12065 0.3048)
			(stroke
				(width 0.1)
				(type default)
			)
			(layer "F.Fab")
		)
		(fp_line
			(start 0.67945 0.3048)
			(end 0.120396 0.3048)
			(stroke
				(width 0.1)
				(type default)
			)
			(layer "F.Fab")
		)
		(fp_line
			(start 0.120396 0.3048)
			(end 0.120396 0.2794)
			(stroke
				(width 0.1)
				(type default)
			)
			(layer "F.Fab")
		)
		(fp_line
			(start -0.12065 0.3048)
			(end -0.67945 0.3048)
			(stroke
				(width 0.1)
				(type default)
			)
			(layer "F.Fab")
		)
		(fp_line
			(start -0.67945 0.3048)
			(end -0.67945 -0.305054)
			(stroke
				(width 0.1)
				(type default)
			)
			(layer "F.Fab")
		)
		(pad "1" smd circle
			(at -0.40005 0 90)
			(size 0 0)
			(layers "F.Cu" "F.Mask" "F.Paste")
			(net "P12V_E1S_0")
		)
		(pad "2" smd circle
			(at 0.40005 0 90)
			(size 0 0)
			(layers "F.Cu" "F.Mask" "F.Paste")
			(net "P12V_E1S_AVIN_PD_0")
		)
	)
	(footprint ""
		(layer "F.Cu")
		(at 36.319968 -132.587238 180)
		(property "Reference" "R3326"
			(at 0 0 180)
			(layer "F.SilkS")
			(hide yes)
			(effects
				(font
					(size 1.27 1.27)
				)
			)
		)
		(property "Value" ""
			(at 0 0 180)
			(layer "F.Fab")
			(effects
				(font
					(size 1.27 1.27)
				)
			)
		)
		(duplicate_pad_numbers_are_jumpers no)
		(fp_line
			(start 0.7874 0.4064)
			(end -0.7874 0.4064)
			(stroke
				(width 0.1524)
				(type default)
			)
			(layer "F.SilkS")
		)
		(fp_line
			(start 0.7874 -0.4064)
			(end 0.7874 0.4064)
			(stroke
				(width 0.1524)
				(type default)
			)
			(layer "F.SilkS")
		)
		(fp_line
			(start -0.7874 0.4064)
			(end -0.7874 -0.4064)
			(stroke
				(width 0.1524)
				(type default)
			)
			(layer "F.SilkS")
		)
		(fp_line
			(start -0.7874 -0.4064)
			(end 0.7874 -0.4064)
			(stroke
				(width 0.1524)
				(type default)
			)
			(layer "F.SilkS")
		)
		(fp_line
			(start 0.67945 0.3048)
			(end 0.120396 0.3048)
			(stroke
				(width 0.1)
				(type default)
			)
			(layer "F.Fab")
		)
		(fp_line
			(start 0.67945 -0.3048)
			(end 0.67945 0.3048)
			(stroke
				(width 0.1)
				(type default)
			)
			(layer "F.Fab")
		)
		(fp_line
			(start 0.12065 -0.2794)
			(end 0.12065 -0.3048)
			(stroke
				(width 0.1)
				(type default)
			)
			(layer "F.Fab")
		)
		(fp_line
			(start 0.12065 -0.3048)
			(end 0.67945 -0.3048)
			(stroke
				(width 0.1)
				(type default)
			)
			(layer "F.Fab")
		)
		(fp_line
			(start 0.120396 0.3048)
			(end 0.120396 0.2794)
			(stroke
				(width 0.1)
				(type default)
			)
			(layer "F.Fab")
		)
		(fp_line
			(start 0.120396 0.2794)
			(end -0.12065 0.2794)
			(stroke
				(width 0.1)
				(type default)
			)
			(layer "F.Fab")
		)
		(fp_line
			(start -0.12065 0.3048)
			(end -0.67945 0.3048)
			(stroke
				(width 0.1)
				(type default)
			)
			(layer "F.Fab")
		)
		(fp_line
			(start -0.12065 0.2794)
			(end -0.12065 0.3048)
			(stroke
				(width 0.1)
				(type default)
			)
			(layer "F.Fab")
		)
		(fp_line
			(start -0.12065 -0.2794)
			(end 0.12065 -0.2794)
			(stroke
				(width 0.1)
				(type default)
			)
			(layer "F.Fab")
		)
		(fp_line
			(start -0.12065 -0.305054)
			(end -0.12065 -0.2794)
			(stroke
				(width 0.1)
				(type default)
			)
			(layer "F.Fab")
		)
		(fp_line
			(start -0.67945 0.3048)
			(end -0.67945 -0.305054)
			(stroke
				(width 0.1)
				(type default)
			)
			(layer "F.Fab")
		)
		(fp_line
			(start -0.67945 -0.305054)
			(end -0.12065 -0.305054)
			(stroke
				(width 0.1)
				(type default)
			)
			(layer "F.Fab")
		)
		(pad "1" smd circle
			(at -0.40005 0 180)
			(size 0 0)
			(layers "F.Cu" "F.Mask" "F.Paste")
			(net "GPU_FPGA_READY_N")
		)
		(pad "2" smd circle
			(at 0.40005 0 180)
			(size 0 0)
			(layers "F.Cu" "F.Mask" "F.Paste")
			(net "GPU_FPGA_READY_R_N")
		)
	)
)
